FILE_TYPE = CONNECTIVITY;
{Allegro Design Entry HDL 17.4-2019 S026 (4007227) 1/17/2022}
"PAGE_NUMBER" = 93;
0"NC";
1"GND\g";
2"P3V3\g";
3"M_I_CPU0_SA_DQ<31:0>";
4"M_I_CPU0_SA_CB<7:0>";
5"M_I_CPU0_SB_CB<7:0>";
6"M_I_CPU0_SA_CA<6:0>";
7"M_I_CPU0_SB_CA<6:0>";
8"M_I_CPU0_SB_DQ<31:0>";
9"M_I_CPU0_SA_DQS_DN<9:0>";
10"M_I_CPU0_SA_DQS_DP<9:0>";
11"M_I_CPU0_SB_DQS_DP<9:0>";
12"M_I_CPU0_SB_DQS_DN<9:0>";
13"M_I_CPU0_SB_CB<0>";
14"P3V3_AUX\g";
15"I3C_SPD_DDRGL_CPU0_SDA";
16"PWRGD_CHI_CPU0_DIMM";
17"I3C_SPD_DDRI_CPU0_SDA";
18"I3C_SPD_DDRGL_CPU0_SCL";
19"PD_CHI_CPU0_DIMM_SAA";
20"I3C_SPD_DDRI_CPU0_SCL";
21"M_I_CPU0_RESET_N";
22"M_I_CPU0_SA_RSP<0>";
23"M_I_CPU0_SB_RSP<0>";
24"PD_CHI_CPU0_DIMM_SAA";
25"M_I_CPU0_SB_CB<2>";
26"M_I_CPU0_CLK_DN<0>";
27"M_I_CPU0_SA_CB<6>";
28"M_I_CPU0_SA_CB<3>";
29"M_I_CPU0_SB_CA<4>";
30"M_I_CPU0_SB_DQS_DP<9>";
31"M_I_CPU0_SB_DQS_DN<9>";
32"M_I_CPU0_SA_DQS_DP<9>";
33"M_I_CPU0_SA_DQS_DN<9>";
34"M_I_CPU0_SA_DQS_DP<8>";
35"M_I_CPU0_SA_DQS_DN<8>";
36"M_I_CPU0_SB_DQS_DN<7>";
37"M_I_CPU0_SA_DQS_DP<7>";
38"M_I_CPU0_SB_DQS_DP<6>";
39"M_I_CPU0_SB_DQS_DN<6>";
40"M_I_CPU0_SA_DQS_DN<6>";
41"M_I_CPU0_SB_DQS_DP<5>";
42"M_I_CPU0_SB_DQS_DN<5>";
43"M_I_CPU0_SA_DQS_DP<5>";
44"M_I_CPU0_SA_DQS_DN<5>";
45"M_I_CPU0_SB_DQS_DP<4>";
46"M_I_CPU0_SB_DQS_DN<4>";
47"M_I_CPU0_SA_DQS_DP<4>";
48"M_I_CPU0_SA_DQS_DN<4>";
49"M_I_CPU0_SB_DQS_DP<3>";
50"M_I_CPU0_SB_DQS_DN<3>";
51"M_I_CPU0_SA_DQS_DP<3>";
52"M_I_CPU0_SA_DQS_DN<3>";
53"M_I_CPU0_SB_DQS_DP<2>";
54"M_I_CPU0_SB_DQS_DN<2>";
55"M_I_CPU0_SA_DQS_DP<2>";
56"M_I_CPU0_SA_DQS_DN<2>";
57"M_I_CPU0_SB_DQS_DP<1>";
58"M_I_CPU0_SB_DQS_DN<1>";
59"M_I_CPU0_SA_DQS_DP<1>";
60"M_I_CPU0_SA_DQS_DN<1>";
61"M_I_CPU0_SB_DQS_DP<0>";
62"M_I_CPU0_SB_DQS_DN<0>";
63"M_I_CPU0_SA_DQS_DP<0>";
64"M_I_CPU0_SA_DQS_DN<0>";
65"M_I_CPU0_SB_DQS_DP<7>";
66"M_I_CPU0_SB_DQS_DN<8>";
67"M_I_CPU0_SB_DQS_DP<8>";
68"M_I_CPU0_SA_DQS_DP<6>";
69"M_I_CPU0_SA_DQS_DN<7>";
70"M_I_CPU0_SB_PAR";
71"M_I_CPU0_SA_PAR";
72"M_I_CPU0_SB_DQ<0>";
73"M_I_CPU0_SB_DQ<1>";
74"M_I_CPU0_SB_DQ<2>";
75"M_I_CPU0_SB_DQ<3>";
76"M_I_CPU0_SB_DQ<4>";
77"M_I_CPU0_SB_DQ<5>";
78"M_I_CPU0_SB_DQ<6>";
79"M_I_CPU0_SB_DQ<7>";
80"M_I_CPU0_SB_DQ<8>";
81"M_I_CPU0_SB_DQ<9>";
82"M_I_CPU0_SB_DQ<10>";
83"M_I_CPU0_SB_DQ<11>";
84"M_I_CPU0_SB_DQ<12>";
85"M_I_CPU0_SB_DQ<13>";
86"M_I_CPU0_SB_DQ<14>";
87"M_I_CPU0_SB_DQ<15>";
88"M_I_CPU0_SB_DQ<16>";
89"M_I_CPU0_SB_DQ<17>";
90"M_I_CPU0_SB_DQ<18>";
91"M_I_CPU0_SB_DQ<19>";
92"M_I_CPU0_SB_DQ<20>";
93"M_I_CPU0_SB_DQ<21>";
94"M_I_CPU0_SB_DQ<22>";
95"M_I_CPU0_SB_DQ<23>";
96"M_I_CPU0_SB_DQ<24>";
97"M_I_CPU0_SB_DQ<25>";
98"M_I_CPU0_SB_DQ<26>";
99"M_I_CPU0_SB_DQ<27>";
100"M_I_CPU0_SB_DQ<28>";
101"M_I_CPU0_SB_DQ<29>";
102"M_I_CPU0_SB_DQ<30>";
103"M_I_CPU0_SB_DQ<31>";
104"M_I_CPU0_SA_DQ<0>";
105"M_I_CPU0_SA_DQ<1>";
106"M_I_CPU0_SA_DQ<2>";
107"M_I_CPU0_SA_DQ<3>";
108"M_I_CPU0_SA_DQ<4>";
109"M_I_CPU0_SA_DQ<5>";
110"M_I_CPU0_SA_DQ<6>";
111"M_I_CPU0_SA_DQ<7>";
112"M_I_CPU0_SA_DQ<8>";
113"M_I_CPU0_SA_DQ<9>";
114"M_I_CPU0_SA_DQ<10>";
115"M_I_CPU0_SA_DQ<11>";
116"M_I_CPU0_SA_DQ<12>";
117"M_I_CPU0_SA_DQ<13>";
118"M_I_CPU0_SA_DQ<14>";
119"M_I_CPU0_SA_DQ<15>";
120"M_I_CPU0_SA_DQ<16>";
121"M_I_CPU0_SA_DQ<17>";
122"M_I_CPU0_SA_DQ<18>";
123"M_I_CPU0_SA_DQ<19>";
124"M_I_CPU0_SA_DQ<20>";
125"M_I_CPU0_SA_DQ<21>";
126"M_I_CPU0_SA_DQ<22>";
127"M_I_CPU0_SA_DQ<23>";
128"M_I_CPU0_SA_DQ<24>";
129"M_I_CPU0_SA_DQ<25>";
130"M_I_CPU0_SA_DQ<26>";
131"M_I_CPU0_SA_DQ<27>";
132"M_I_CPU0_SA_DQ<28>";
133"M_I_CPU0_SA_DQ<29>";
134"M_I_CPU0_SA_DQ<30>";
135"M_I_CPU0_SB_CS_N<1>";
136"M_I_CPU0_SA_CS_N<1>";
137"M_I_CPU0_SB_CS_N<0>";
138"M_I_CPU0_SA_CS_N<0>";
139"M_I_CPU0_CLK_DP<0>";
140"M_I_CPU0_SB_CB<1>";
141"M_I_CPU0_SB_CB<3>";
142"M_I_CPU0_SB_CB<4>";
143"M_I_CPU0_SB_CB<5>";
144"M_I_CPU0_SB_CB<6>";
145"M_I_CPU0_SA_CB<0>";
146"M_I_CPU0_SA_CB<2>";
147"M_I_CPU0_SA_CB<5>";
148"M_I_CPU0_SB_CA<6>";
149"M_I_CPU0_SA_CA<6>";
150"M_I_CPU0_SB_CA<5>";
151"M_I_CPU0_SA_CA<5>";
152"M_I_CPU0_SA_CA<4>";
153"M_I_CPU0_SB_CA<3>";
154"M_I_CPU0_SA_CA<3>";
155"M_I_CPU0_SB_CA<2>";
156"M_I_CPU0_SA_CA<2>";
157"M_I_CPU0_SB_CA<1>";
158"M_I_CPU0_SA_CA<1>";
159"M_I_CPU0_SB_CA<0>";
160"M_I_CPU0_SA_CA<0>";
161"M_I_CPU0_SB_CB<7>";
162"M_I_CPU0_SA_CB<1>";
163"M_I_CPU0_SA_CB<4>";
164"M_I_CPU0_SA_CB<7>";
165"M_I_CPU0_SA_DQ<31>";
166"PWRGD_CHGL_CPU0";
167"M_I_CPU0_ALERT_N";
168"GND\g";
169"GND\g";
170"GND\g";
171"P12V_MEM_CPU0\g";
172"GND\g";
%"TAP"
"1","(-6000,4250)","0","mstr_standard","I100";
;
CDS_LIB"mstr_standard"
BODY_TYPE"PLUMBING"
HDL_TAP"TRUE";
"B \NAC \NWC"3;
"S \NAC"
BN"7"111;
%"TAP"
"1","(-6000,4300)","0","mstr_standard","I101";
;
CDS_LIB"mstr_standard"
BODY_TYPE"PLUMBING"
HDL_TAP"TRUE";
"B \NAC \NWC"3;
"S \NAC"
BN"8"112;
%"TAP"
"1","(-6000,4350)","0","mstr_standard","I102";
;
CDS_LIB"mstr_standard"
BODY_TYPE"PLUMBING"
HDL_TAP"TRUE";
"B \NAC \NWC"3;
"S \NAC"
BN"9"113;
%"TAP"
"1","(-6000,4450)","0","mstr_standard","I103";
;
CDS_LIB"mstr_standard"
BODY_TYPE"PLUMBING"
HDL_TAP"TRUE";
"B \NAC \NWC"3;
"S \NAC"
BN"11"115;
%"TAP"
"1","(-6000,4400)","0","mstr_standard","I104";
;
CDS_LIB"mstr_standard"
BODY_TYPE"PLUMBING"
HDL_TAP"TRUE";
"B \NAC \NWC"3;
"S \NAC"
BN"10"114;
%"TAP"
"1","(-6000,4500)","0","mstr_standard","I105";
;
CDS_LIB"mstr_standard"
BODY_TYPE"PLUMBING"
HDL_TAP"TRUE";
"B \NAC \NWC"3;
"S \NAC"
BN"12"116;
%"TAP"
"1","(-6000,4550)","0","mstr_standard","I106";
;
CDS_LIB"mstr_standard"
BODY_TYPE"PLUMBING"
HDL_TAP"TRUE";
"B \NAC \NWC"3;
"S \NAC"
BN"13"117;
%"TAP"
"1","(-6000,4600)","0","mstr_standard","I107";
;
CDS_LIB"mstr_standard"
BODY_TYPE"PLUMBING"
HDL_TAP"TRUE";
"B \NAC \NWC"3;
"S \NAC"
BN"14"118;
%"TAP"
"1","(-6000,4700)","0","mstr_standard","I108";
;
CDS_LIB"mstr_standard"
BODY_TYPE"PLUMBING"
HDL_TAP"TRUE";
"B \NAC \NWC"3;
"S \NAC"
BN"16"120;
%"TAP"
"1","(-6000,4650)","0","mstr_standard","I109";
;
CDS_LIB"mstr_standard"
BODY_TYPE"PLUMBING"
HDL_TAP"TRUE";
"B \NAC \NWC"3;
"S \NAC"
BN"15"119;
%"TAP"
"1","(-6000,4800)","0","mstr_standard","I110";
;
CDS_LIB"mstr_standard"
BODY_TYPE"PLUMBING"
HDL_TAP"TRUE";
"B \NAC \NWC"3;
"S \NAC"
BN"18"122;
%"TAP"
"1","(-6000,4750)","0","mstr_standard","I111";
;
CDS_LIB"mstr_standard"
BODY_TYPE"PLUMBING"
HDL_TAP"TRUE";
"B \NAC \NWC"3;
"S \NAC"
BN"17"121;
%"TAP"
"1","(-6000,4850)","0","mstr_standard","I112";
;
CDS_LIB"mstr_standard"
BODY_TYPE"PLUMBING"
HDL_TAP"TRUE";
"B \NAC \NWC"3;
"S \NAC"
BN"19"123;
%"TAP"
"1","(-6000,4950)","0","mstr_standard","I113";
;
CDS_LIB"mstr_standard"
BODY_TYPE"PLUMBING"
HDL_TAP"TRUE";
"B \NAC \NWC"3;
"S \NAC"
BN"21"125;
%"TAP"
"1","(-6000,4900)","0","mstr_standard","I114";
;
CDS_LIB"mstr_standard"
BODY_TYPE"PLUMBING"
HDL_TAP"TRUE";
"B \NAC \NWC"3;
"S \NAC"
BN"20"124;
%"TAP"
"1","(-6000,5000)","0","mstr_standard","I115";
;
CDS_LIB"mstr_standard"
BODY_TYPE"PLUMBING"
HDL_TAP"TRUE";
"B \NAC \NWC"3;
"S \NAC"
BN"22"126;
%"TAP"
"1","(-6000,5050)","0","mstr_standard","I116";
;
CDS_LIB"mstr_standard"
BODY_TYPE"PLUMBING"
HDL_TAP"TRUE";
"B \NAC \NWC"3;
"S \NAC"
BN"23"127;
%"TAP"
"1","(-6000,5150)","0","mstr_standard","I117";
;
CDS_LIB"mstr_standard"
BODY_TYPE"PLUMBING"
HDL_TAP"TRUE";
"B \NAC \NWC"3;
"S \NAC"
BN"25"129;
%"TAP"
"1","(-6000,5100)","0","mstr_standard","I118";
;
CDS_LIB"mstr_standard"
BODY_TYPE"PLUMBING"
HDL_TAP"TRUE";
"B \NAC \NWC"3;
"S \NAC"
BN"24"128;
%"TAP"
"1","(-6000,5200)","0","mstr_standard","I119";
;
CDS_LIB"mstr_standard"
BODY_TYPE"PLUMBING"
HDL_TAP"TRUE";
"B \NAC \NWC"3;
"S \NAC"
BN"26"130;
%"TAP"
"1","(-6000,5350)","0","mstr_standard","I120";
;
CDS_LIB"mstr_standard"
BODY_TYPE"PLUMBING"
HDL_TAP"TRUE";
"B \NAC \NWC"3;
"S \NAC"
BN"29"133;
%"TAP"
"1","(-6000,5300)","0","mstr_standard","I121";
;
CDS_LIB"mstr_standard"
BODY_TYPE"PLUMBING"
HDL_TAP"TRUE";
"B \NAC \NWC"3;
"S \NAC"
BN"28"132;
%"TAP"
"1","(-6000,5250)","0","mstr_standard","I122";
;
CDS_LIB"mstr_standard"
BODY_TYPE"PLUMBING"
HDL_TAP"TRUE";
"B \NAC \NWC"3;
"S \NAC"
BN"27"131;
%"TAP"
"1","(-6000,5400)","0","mstr_standard","I123";
;
CDS_LIB"mstr_standard"
BODY_TYPE"PLUMBING"
HDL_TAP"TRUE";
"B \NAC \NWC"3;
"S \NAC"
BN"30"134;
%"TAP"
"1","(-6000,5450)","0","mstr_standard","I124";
;
CDS_LIB"mstr_standard"
BODY_TYPE"PLUMBING"
HDL_TAP"TRUE";
"B \NAC \NWC"3;
"S \NAC"
BN"31"165;
%"GND"
"1","(-6425,1150)","0","mstr_symbols","I127";
;
VOLTAGE"0.0"
SIZE"1B"
CDS_LIB"mstr_symbols"
BOM_COST"MEM"
BODY_TYPE"PLUMBING"
HDL_POWER"GND";
"A\NAC"172;
%"Q_RES"
"2","(-6425,1300)","0","pure_quanta","I128";
;
LOCATION"R766"
$SEC"1"
CDS_SEC"1"
WATTAGE"1/16W"
MATERIAL"CHIP"
TOLERANCE"1%"
VALUE"23.2K"
PACK_TYPE"0402LF"
CDS_LIB"pure_quanta"
PART_NUMBER"CS32322FB03";
"A"
$PN"1"24;
"B"
$PN"2"172;
%"GND"
"1","(-2125,2025)","0","mstr_symbols","I141";
;
VOLTAGE"0.0"
SIZE"1B"
CDS_LIB"mstr_symbols"
BODY_TYPE"PLUMBING"
HDL_POWER"GND";
"A\NAC"168;
%"GND"
"1","(-325,1800)","0","mstr_symbols","I142";
;
VOLTAGE"0.0"
SIZE"1B"
CDS_LIB"mstr_symbols"
BODY_TYPE"PLUMBING"
HDL_POWER"GND";
"A\NAC"169;
%"SCONN288_DDR506112002KQ"
"3","(-1225,3800)","0","pure_quanta","I143";
;
LOCATION"J18"
$SEC"3"
CDS_SEC"3"
MATERIAL"IO"
PART_TYPE"SMLF"
VALUE"SCONN288_DDR506112002KQ"
CDS_LIB"pure_quanta"
NEEDS_NO_SIZE"TRUE"
CDS_LMAN_SYM_OUTLINE"-450,1800,450,-1750"
PART_NUMBER"DFHST8FS479";
"G3"
$PN"G3"169;
"G2"
$PN"G2"169;
"G1"
$PN"G1"169;
"VSS62"
$PN"141"169;
"VSS61"
$PN"139"169;
"VSS60"
$PN"136"169;
"VSS58"
$PN"132"169;
"VSS104"
$PN"240"168;
"VSS102"
$PN"235"168;
"VSS100"
$PN"230"168;
"VIN_BULK2"
$PN"146"171;
"VIN_BULK1"
$PN"145"171;
"VIN_BULK0"
$PN"1"171;
"VSS126"
$PN"288"168;
"VSS125"
$PN"286"168;
"VSS124"
$PN"284"168;
"VSS123"
$PN"281"168;
"VSS122"
$PN"279"168;
"VSS121"
$PN"277"168;
"VSS120"
$PN"275"168;
"VSS119"
$PN"273"168;
"VSS118"
$PN"270"168;
"VSS117"
$PN"268"168;
"VSS116"
$PN"266"168;
"VSS115"
$PN"264"168;
"VSS114"
$PN"262"168;
"VSS113"
$PN"259"168;
"VSS112"
$PN"257"168;
"VSS111"
$PN"255"168;
"VSS110"
$PN"253"168;
"VSS109"
$PN"251"168;
"VSS108"
$PN"248"168;
"VSS107"
$PN"246"168;
"VSS106"
$PN"244"168;
"VSS105"
$PN"242"168;
"VSS103"
$PN"237"168;
"VSS101"
$PN"233"168;
"VSS99"
$PN"228"168;
"VSS98"
$PN"226"168;
"VSS97"
$PN"224"168;
"VSS96"
$PN"222"168;
"VSS95"
$PN"219"168;
"VSS94"
$PN"216"168;
"VSS93"
$PN"214"168;
"VSS92"
$PN"212"168;
"VSS91"
$PN"210"168;
"VSS90"
$PN"208"168;
"VSS89"
$PN"206"168;
"VSS88"
$PN"204"168;
"VSS87"
$PN"202"168;
"VSS86"
$PN"199"168;
"VSS85"
$PN"197"168;
"VSS84"
$PN"195"168;
"VSS83"
$PN"193"168;
"VSS82"
$PN"191"168;
"VSS81"
$PN"188"168;
"VSS80"
$PN"186"168;
"VSS79"
$PN"184"168;
"VSS78"
$PN"182"168;
"VSS77"
$PN"180"168;
"VSS76"
$PN"177"168;
"VSS75"
$PN"175"168;
"VSS74"
$PN"173"168;
"VSS73"
$PN"171"168;
"VSS72"
$PN"169"168;
"VSS71"
$PN"166"168;
"VSS70"
$PN"164"168;
"VSS69"
$PN"162"168;
"VSS68"
$PN"160"168;
"VSS67"
$PN"158"168;
"VSS66"
$PN"155"168;
"VSS65"
$PN"153"168;
"VSS64"
$PN"151"168;
"VSS63"
$PN"143"169;
"VSS59"
$PN"134"169;
"VSS57"
$PN"130"169;
"VSS56"
$PN"128"169;
"VSS55"
$PN"125"169;
"VSS54"
$PN"123"169;
"VSS53"
$PN"121"169;
"VSS52"
$PN"119"169;
"VSS51"
$PN"117"169;
"VSS50"
$PN"114"169;
"VSS49"
$PN"112"169;
"VSS48"
$PN"110"169;
"VSS47"
$PN"108"169;
"VSS46"
$PN"106"169;
"VSS45"
$PN"103"169;
"VSS44"
$PN"101"169;
"VSS43"
$PN"99"169;
"VSS42"
$PN"97"169;
"VSS41"
$PN"95"169;
"VSS40"
$PN"92"169;
"VSS39"
$PN"90"169;
"VSS38"
$PN"88"169;
"VSS37"
$PN"85"169;
"VSS36"
$PN"83"169;
"VSS35"
$PN"81"169;
"VSS34"
$PN"79"169;
"VSS33"
$PN"77"169;
"VSS32"
$PN"75"169;
"VSS31"
$PN"73"169;
"VSS30"
$PN"71"169;
"VSS29"
$PN"69"169;
"VSS28"
$PN"67"169;
"VSS27"
$PN"65"169;
"VSS26"
$PN"63"169;
"VSS25"
$PN"61"169;
"VSS24"
$PN"59"169;
"VSS23"
$PN"57"169;
"VSS22"
$PN"54"169;
"VSS21"
$PN"52"169;
"VSS20"
$PN"50"169;
"VSS19"
$PN"48"169;
"VSS18"
$PN"46"169;
"VSS17"
$PN"43"169;
"VSS16"
$PN"41"169;
"VSS15"
$PN"39"169;
"VSS14"
$PN"37"169;
"VSS13"
$PN"35"169;
"VSS12"
$PN"32"169;
"VSS11"
$PN"30"169;
"VSS10"
$PN"28"169;
"VSS9"
$PN"26"169;
"VSS8"
$PN"24"169;
"VSS7"
$PN"21"169;
"VSS6"
$PN"19"169;
"VSS5"
$PN"17"169;
"VSS4"
$PN"15"169;
"VSS3"
$PN"13"169;
"VSS2"
$PN"10"169;
"VSS1"
$PN"8"169;
"VSS0"
$PN"6"169;
%"Q_CAP"
"1","(-8650,3275)","2","pure_quanta","I185";
;
LOCATION"C120"
$SEC"1"
CDS_SEC"1"
TOLERANCE"10%"
MATERIAL"X7R"
VALUE"0.1UF"
VOLTAGE"25V"
PACK_TYPE"0402"
BOM_COST"MEM"
CDS_LIB"pure_quanta"
ROOM""
PART_NUMBER"CH4104K1B00";
"B"
$PN"2"1;
"A"
$PN"1"14;
%"GND"
"1","(-8650,3050)","0","mstr_symbols","I186";
;
ROOM"MEM_EFGH_DECOUPLING_CAPS"
VOLTAGE"0"
CDS_LIB"mstr_symbols"
SIZE"1B"
BOM_COST"MEM"
BODY_TYPE"PLUMBING"
HDL_POWER"GND";
"A\NAC"1;
%"Q_RES"
"1","(-8475,2200)","2","pure_quanta","I188";
;
LOCATION"R299"
$SEC"1"
CDS_SEC"1"
VALUE"1K"
PACK_TYPE"0402LF"
MATERIAL"CHIP"
WATTAGE"1/16W"
CDS_LIB"pure_quanta"
BOM_COST"MEM"
TOLERANCE"1%"
ROOM""
PART_NUMBER"CS21002FB06";
"B"
$PN"2"166;
"A"
$PN"1"16;
%"Q_RES"
"2","(-8350,2350)","0","pure_quanta","I189";
;
LOCATION"R98"
$SEC"1"
CDS_SEC"1"
PACK_TYPE"0402LF"
VALUE"1K"
MATERIAL"EMPTY"
WATTAGE"1/16W"
TOLERANCE"1%"
CDS_LIB"pure_quanta"
BOM_COST"MEM"
ROOM""
PART_NUMBER"CS21002FB06";
"A"
$PN"1"2;
"B"
$PN"2"16;
%"VCC_CORE"
"1","(-8350,2525)","0","mstr_symbols","I190";
;
HDL_POWER"P3V3"
ROOM"PVCCINFAON_CPU0_CTRL"
VOLTAGE"3.3"
CDS_LIB"mstr_symbols";
"A"2;
%"TAP"
"1","(-3450,4100)","0","mstr_standard","I191";
;
CDS_LIB"mstr_standard"
BODY_TYPE"PLUMBING"
HDL_TAP"TRUE";
"B \NAC \NWC"10;
"S \NAC"
BN"5"43;
%"TAP"
"1","(-3250,4450)","0","mstr_standard","I197";
;
CDS_LIB"mstr_standard"
BODY_TYPE"PLUMBING"
HDL_TAP"TRUE";
"B \NAC \NWC"9;
"S \NAC"
BN"9"33;
%"TAP"
"1","(-3250,4350)","0","mstr_standard","I198";
;
CDS_LIB"mstr_standard"
BODY_TYPE"PLUMBING"
HDL_TAP"TRUE";
"B \NAC \NWC"9;
"S \NAC"
BN"8"35;
%"TAP"
"1","(-3450,4400)","0","mstr_standard","I199";
;
CDS_LIB"mstr_standard"
BODY_TYPE"PLUMBING"
HDL_TAP"TRUE";
"B \NAC \NWC"10;
"S \NAC"
BN"8"34;
%"TAP"
"1","(-3450,4500)","0","mstr_standard","I200";
;
CDS_LIB"mstr_standard"
BODY_TYPE"PLUMBING"
HDL_TAP"TRUE";
"B \NAC \NWC"10;
"S \NAC"
BN"9"32;
%"TAP"
"1","(-3250,4250)","0","mstr_standard","I201";
;
CDS_LIB"mstr_standard"
BODY_TYPE"PLUMBING"
HDL_TAP"TRUE";
"B \NAC \NWC"9;
"S \NAC"
BN"7"69;
%"TAP"
"1","(-3250,4150)","0","mstr_standard","I202";
;
CDS_LIB"mstr_standard"
BODY_TYPE"PLUMBING"
HDL_TAP"TRUE";
"B \NAC \NWC"9;
"S \NAC"
BN"6"40;
%"TAP"
"1","(-3250,4050)","0","mstr_standard","I203";
;
CDS_LIB"mstr_standard"
BODY_TYPE"PLUMBING"
HDL_TAP"TRUE";
"B \NAC \NWC"9;
"S \NAC"
BN"5"44;
%"TAP"
"1","(-3250,3950)","0","mstr_standard","I204";
;
CDS_LIB"mstr_standard"
BODY_TYPE"PLUMBING"
HDL_TAP"TRUE";
"B \NAC \NWC"9;
"S \NAC"
BN"4"48;
%"TAP"
"1","(-3250,3850)","0","mstr_standard","I205";
;
CDS_LIB"mstr_standard"
BODY_TYPE"PLUMBING"
HDL_TAP"TRUE";
"B \NAC \NWC"9;
"S \NAC"
BN"3"52;
%"TAP"
"1","(-3250,3750)","0","mstr_standard","I206";
;
CDS_LIB"mstr_standard"
BODY_TYPE"PLUMBING"
HDL_TAP"TRUE";
"B \NAC \NWC"9;
"S \NAC"
BN"2"56;
%"TAP"
"1","(-3250,3650)","0","mstr_standard","I207";
;
CDS_LIB"mstr_standard"
BODY_TYPE"PLUMBING"
HDL_TAP"TRUE";
"B \NAC \NWC"9;
"S \NAC"
BN"1"60;
%"TAP"
"1","(-3250,3400)","0","mstr_standard","I208";
;
CDS_LIB"mstr_standard"
BODY_TYPE"PLUMBING"
HDL_TAP"TRUE";
"B \NAC \NWC"12;
"S \NAC"
BN"9"31;
%"TAP"
"1","(-3250,3550)","0","mstr_standard","I209";
;
CDS_LIB"mstr_standard"
BODY_TYPE"PLUMBING"
HDL_TAP"TRUE";
"B \NAC \NWC"9;
"S \NAC"
BN"0"64;
%"TAP"
"1","(-3450,4300)","0","mstr_standard","I210";
;
CDS_LIB"mstr_standard"
BODY_TYPE"PLUMBING"
HDL_TAP"TRUE";
"B \NAC \NWC"10;
"S \NAC"
BN"7"37;
%"TAP"
"1","(-3450,4200)","0","mstr_standard","I211";
;
CDS_LIB"mstr_standard"
BODY_TYPE"PLUMBING"
HDL_TAP"TRUE";
"B \NAC \NWC"10;
"S \NAC"
BN"6"68;
%"TAP"
"1","(-3450,4000)","0","mstr_standard","I212";
;
CDS_LIB"mstr_standard"
BODY_TYPE"PLUMBING"
HDL_TAP"TRUE";
"B \NAC \NWC"10;
"S \NAC"
BN"4"47;
%"TAP"
"1","(-3450,3900)","0","mstr_standard","I213";
;
CDS_LIB"mstr_standard"
BODY_TYPE"PLUMBING"
HDL_TAP"TRUE";
"B \NAC \NWC"10;
"S \NAC"
BN"3"51;
%"TAP"
"1","(-3450,3700)","0","mstr_standard","I214";
;
CDS_LIB"mstr_standard"
BODY_TYPE"PLUMBING"
HDL_TAP"TRUE";
"B \NAC \NWC"10;
"S \NAC"
BN"1"59;
%"TAP"
"1","(-3450,3800)","0","mstr_standard","I215";
;
CDS_LIB"mstr_standard"
BODY_TYPE"PLUMBING"
HDL_TAP"TRUE";
"B \NAC \NWC"10;
"S \NAC"
BN"2"55;
%"TAP"
"1","(-3450,3600)","0","mstr_standard","I216";
;
CDS_LIB"mstr_standard"
BODY_TYPE"PLUMBING"
HDL_TAP"TRUE";
"B \NAC \NWC"10;
"S \NAC"
BN"0"63;
%"TAP"
"1","(-3450,3350)","0","mstr_standard","I217";
;
CDS_LIB"mstr_standard"
BODY_TYPE"PLUMBING"
HDL_TAP"TRUE";
"B \NAC \NWC"11;
"S \NAC"
BN"8"67;
%"TAP"
"1","(-3450,3450)","0","mstr_standard","I218";
;
CDS_LIB"mstr_standard"
BODY_TYPE"PLUMBING"
HDL_TAP"TRUE";
"B \NAC \NWC"11;
"S \NAC"
BN"9"30;
%"TAP"
"1","(-3250,3300)","0","mstr_standard","I219";
;
CDS_LIB"mstr_standard"
BODY_TYPE"PLUMBING"
HDL_TAP"TRUE";
"B \NAC \NWC"12;
"S \NAC"
BN"8"66;
%"SCONN288_DDR506112002KQ"
"1","(-6850,3700)","0","pure_quanta","I22";
;
LOCATION"J18"
$SEC"1"
CDS_SEC"1"
PART_TYPE"SMLF"
VALUE"SCONN288_DDR506112002KQ"
MATERIAL"IO"
CDS_LIB"pure_quanta"
NEEDS_NO_SIZE"TRUE"
CDS_LMAN_SYM_OUTLINE"-450,1900,450,-1850"
PART_NUMBER"DFHST8FS479";
"PWR_GOOD||FAIL_N"
$PN"147"16;
"DQ31_A"
$PN"194"165;
"CB7_A"
$PN"205"164;
"CB4_A"
$PN"58"163;
"CB1_A"
$PN"53"162;
"CB7_B"
$PN"236"161;
"ALERT_N \B"
$PN"62"167;
"CA0_A"
$PN"66"160;
"CA0_B"
$PN"76"159;
"CA1_A"
$PN"211"158;
"CA1_B"
$PN"221"157;
"CA2_A"
$PN"68"156;
"CA2_B"
$PN"78"155;
"CA3_A"
$PN"213"154;
"CA3_B"
$PN"223"153;
"CA4_A"
$PN"70"152;
"CA4_B"
$PN"80"29;
"CA5_A"
$PN"215"151;
"CA5_B"
$PN"225"150;
"CA6_A"
$PN"72"149;
"CA6_B"
$PN"82"148;
"CB6_A"
$PN"203"27;
"CB5_A"
$PN"60"147;
"CB3_A"
$PN"198"28;
"CB2_A"
$PN"196"146;
"CB0_A"
$PN"51"145;
"CB6_B"
$PN"234"144;
"CB5_B"
$PN"91"143;
"CB4_B"
$PN"89"142;
"CB3_B"
$PN"243"141;
"CB2_B"
$PN"241"25;
"CB1_B"
$PN"98"140;
"CB0_B"
$PN"96"13;
"CK_C \B"
$PN"218"26;
"CK_T"
$PN"217"139;
"CS0_A_N"
$PN"64"138;
"CS0_B_N"
$PN"84"137;
"CS1_A_N"
$PN"209"136;
"CS1_B_N"
$PN"229"135;
"DQ30_A"
$PN"192"134;
"DQ29_A"
$PN"49"133;
"DQ28_A"
$PN"47"132;
"DQ27_A"
$PN"187"131;
"DQ26_A"
$PN"185"130;
"DQ25_A"
$PN"42"129;
"DQ24_A"
$PN"40"128;
"DQ23_A"
$PN"183"127;
"DQ22_A"
$PN"181"126;
"DQ21_A"
$PN"38"125;
"DQ20_A"
$PN"36"124;
"DQ19_A"
$PN"176"123;
"DQ18_A"
$PN"174"122;
"DQ17_A"
$PN"31"121;
"DQ16_A"
$PN"29"120;
"DQ15_A"
$PN"172"119;
"DQ14_A"
$PN"170"118;
"DQ13_A"
$PN"27"117;
"DQ12_A"
$PN"25"116;
"DQ11_A"
$PN"165"115;
"DQ10_A"
$PN"163"114;
"DQ9_A"
$PN"20"113;
"DQ8_A"
$PN"18"112;
"DQ7_A"
$PN"161"111;
"DQ6_A"
$PN"159"110;
"DQ5_A"
$PN"16"109;
"DQ4_A"
$PN"14"108;
"DQ3_A"
$PN"154"107;
"DQ2_A"
$PN"152"106;
"DQ1_A"
$PN"9"105;
"DQ0_A"
$PN"7"104;
"DQ31_B"
$PN"287"103;
"DQ30_B"
$PN"285"102;
"DQ29_B"
$PN"142"101;
"DQ28_B"
$PN"140"100;
"DQ27_B"
$PN"280"99;
"DQ26_B"
$PN"278"98;
"DQ25_B"
$PN"135"97;
"DQ24_B"
$PN"133"96;
"DQ23_B"
$PN"276"95;
"DQ22_B"
$PN"274"94;
"DQ21_B"
$PN"131"93;
"DQ20_B"
$PN"129"92;
"DQ19_B"
$PN"269"91;
"DQ18_B"
$PN"267"90;
"DQ17_B"
$PN"124"89;
"DQ16_B"
$PN"122"88;
"DQ15_B"
$PN"265"87;
"DQ14_B"
$PN"263"86;
"DQ13_B"
$PN"120"85;
"DQ12_B"
$PN"118"84;
"DQ11_B"
$PN"258"83;
"DQ10_B"
$PN"256"82;
"DQ9_B"
$PN"113"81;
"DQ8_B"
$PN"111"80;
"DQ7_B"
$PN"254"79;
"DQ6_B"
$PN"252"78;
"DQ5_B"
$PN"109"77;
"DQ4_B"
$PN"107"76;
"DQ3_B"
$PN"247"75;
"DQ2_B"
$PN"245"74;
"DQ1_B"
$PN"102"73;
"DQ0_B"
$PN"100"72;
"HAS"
$PN"148"19;
"HSCL"
$PN"4"20;
"HSDA"
$PN"5"17;
"LBD||RSP_A_N"
$PN"86"22;
"LBS||RSP_B_N"
$PN"87"23;
"PAR_A"
$PN"74"71;
"PAR_B"
$PN"227"70;
"RESET_N \B"
$PN"207"21;
"RFU6"
$PN"232"0;
"RFU5"
$PN"231"0;
"RFU4"
$PN"220"0;
"RFU3"
$PN"150"0;
"RFU2"
$PN"149"0;
"RFU1"
$PN"144"0;
"RFU0"
$PN"2"0;
"VIN_MGMT"
$PN"3"14;
%"TAP"
"1","(-3250,3200)","0","mstr_standard","I220";
;
CDS_LIB"mstr_standard"
BODY_TYPE"PLUMBING"
HDL_TAP"TRUE";
"B \NAC \NWC"12;
"S \NAC"
BN"7"36;
%"TAP"
"1","(-3250,3100)","0","mstr_standard","I221";
;
CDS_LIB"mstr_standard"
BODY_TYPE"PLUMBING"
HDL_TAP"TRUE";
"B \NAC \NWC"12;
"S \NAC"
BN"6"39;
%"TAP"
"1","(-3250,3000)","0","mstr_standard","I222";
;
CDS_LIB"mstr_standard"
BODY_TYPE"PLUMBING"
HDL_TAP"TRUE";
"B \NAC \NWC"12;
"S \NAC"
BN"5"42;
%"TAP"
"1","(-3250,2900)","0","mstr_standard","I223";
;
CDS_LIB"mstr_standard"
BODY_TYPE"PLUMBING"
HDL_TAP"TRUE";
"B \NAC \NWC"12;
"S \NAC"
BN"4"46;
%"TAP"
"1","(-3250,2800)","0","mstr_standard","I224";
;
CDS_LIB"mstr_standard"
BODY_TYPE"PLUMBING"
HDL_TAP"TRUE";
"B \NAC \NWC"12;
"S \NAC"
BN"3"50;
%"TAP"
"1","(-3250,2700)","0","mstr_standard","I225";
;
CDS_LIB"mstr_standard"
BODY_TYPE"PLUMBING"
HDL_TAP"TRUE";
"B \NAC \NWC"12;
"S \NAC"
BN"2"54;
%"TAP"
"1","(-3250,2600)","0","mstr_standard","I226";
;
CDS_LIB"mstr_standard"
BODY_TYPE"PLUMBING"
HDL_TAP"TRUE";
"B \NAC \NWC"12;
"S \NAC"
BN"1"58;
%"TAP"
"1","(-3250,2500)","0","mstr_standard","I227";
;
CDS_LIB"mstr_standard"
BODY_TYPE"PLUMBING"
HDL_TAP"TRUE";
"B \NAC \NWC"12;
"S \NAC"
BN"0"62;
%"TAP"
"1","(-3450,3150)","0","mstr_standard","I228";
;
CDS_LIB"mstr_standard"
BODY_TYPE"PLUMBING"
HDL_TAP"TRUE";
"B \NAC \NWC"11;
"S \NAC"
BN"6"38;
%"TAP"
"1","(-3450,3250)","0","mstr_standard","I229";
;
CDS_LIB"mstr_standard"
BODY_TYPE"PLUMBING"
HDL_TAP"TRUE";
"B \NAC \NWC"11;
"S \NAC"
BN"7"65;
%"TAP"
"1","(-7700,3350)","2","mstr_standard","I23";
;
CDS_LIB"mstr_standard"
BODY_TYPE"PLUMBING"
HDL_TAP"TRUE";
"B \NAC \NWC"5;
"S \NAC"
BN"2"25;
%"TAP"
"1","(-3450,3050)","0","mstr_standard","I230";
;
CDS_LIB"mstr_standard"
BODY_TYPE"PLUMBING"
HDL_TAP"TRUE";
"B \NAC \NWC"11;
"S \NAC"
BN"5"41;
%"TAP"
"1","(-3450,2950)","0","mstr_standard","I231";
;
CDS_LIB"mstr_standard"
BODY_TYPE"PLUMBING"
HDL_TAP"TRUE";
"B \NAC \NWC"11;
"S \NAC"
BN"4"45;
%"TAP"
"1","(-3450,2850)","0","mstr_standard","I232";
;
CDS_LIB"mstr_standard"
BODY_TYPE"PLUMBING"
HDL_TAP"TRUE";
"B \NAC \NWC"11;
"S \NAC"
BN"3"49;
%"TAP"
"1","(-3450,2650)","0","mstr_standard","I233";
;
CDS_LIB"mstr_standard"
BODY_TYPE"PLUMBING"
HDL_TAP"TRUE";
"B \NAC \NWC"11;
"S \NAC"
BN"1"57;
%"TAP"
"1","(-3450,2750)","0","mstr_standard","I234";
;
CDS_LIB"mstr_standard"
BODY_TYPE"PLUMBING"
HDL_TAP"TRUE";
"B \NAC \NWC"11;
"S \NAC"
BN"2"53;
%"TAP"
"1","(-3450,2550)","0","mstr_standard","I235";
;
CDS_LIB"mstr_standard"
BODY_TYPE"PLUMBING"
HDL_TAP"TRUE";
"B \NAC \NWC"11;
"S \NAC"
BN"0"61;
%"SCONN288_DDR506112002KQ"
"2","(-4400,3500)","0","pure_quanta","I236";
;
LOCATION"J18"
$SEC"2"
CDS_SEC"2"
VALUE"SCONN288_DDR506112002KQ"
MATERIAL"IO"
PART_TYPE"SMLF"
CDS_LIB"pure_quanta"
NEEDS_NO_SIZE"TRUE"
CDS_LMAN_SYM_OUTLINE"-600,1150,600,-1150"
PART_NUMBER"DFHST8FS479";
"DQS7_A_C||TDQS7_A_C \B"
$PN"178"69;
"DQS6_A_T||TDQS6_A_T"
$PN"168"68;
"DQS8_B_T||TDQS8_B_T"
$PN"283"67;
"DQS8_B_C||TDQS8_B_C \B"
$PN"282"66;
"DQS7_B_T||TDQS7_B_T"
$PN"272"65;
"DQS0_A_C \B"
$PN"12"64;
"DQS0_A_T"
$PN"11"63;
"DQS0_B_C \B"
$PN"105"62;
"DQS0_B_T"
$PN"104"61;
"DQS1_A_C \B"
$PN"23"60;
"DQS1_A_T"
$PN"22"59;
"DQS1_B_C \B"
$PN"116"58;
"DQS1_B_T"
$PN"115"57;
"DQS2_A_C \B"
$PN"34"56;
"DQS2_A_T"
$PN"33"55;
"DQS2_B_C \B"
$PN"127"54;
"DQS2_B_T"
$PN"126"53;
"DQS3_A_C \B"
$PN"45"52;
"DQS3_A_T"
$PN"44"51;
"DQS3_B_C \B"
$PN"138"50;
"DQS3_B_T"
$PN"137"49;
"DQS4_A_C \B"
$PN"56"48;
"DQS4_A_T"
$PN"55"47;
"DQS4_B_C \B"
$PN"238"46;
"DQS4_B_T"
$PN"239"45;
"DQS5_A_C||TDQS5_A_C||DQS5_A_T||TDQS5_A_T \B"
$PN"156"44;
"DQS5_A_T||TDQS5_A_T"
$PN"157"43;
"DQS5_B_C||TDQS5_B_C \B"
$PN"249"42;
"DQS5_B_T||TDQS5_B_T"
$PN"250"41;
"DQS6_A_C||TDQS6_A_C||DQS6_A_T||TDQS6_A_T \B"
$PN"167"40;
"DQS6_B_C||TDQS6_B_C \B"
$PN"260"39;
"DQS6_B_T||TDQS6_B_T"
$PN"261"38;
"DQS7_A_T||TDQS7_A_T"
$PN"179"37;
"DQS7_B_C||TDQS7_B_C \B"
$PN"271"36;
"DQS8_A_C||TDQS8_A_C \B"
$PN"189"35;
"DQS8_A_T||TDQS8_A_T"
$PN"190"34;
"DQS9_A_C||TDQS9_A_C \B"
$PN"200"33;
"DQS9_A_T||TDQS9_A_T"
$PN"201"32;
"DQS9_B_C||TDQS9_B_C \B"
$PN"94"31;
"DQS9_B_T||TDQS9_B_T||DBI4_B_N"
$PN"93"30;
%"GND"
"1","(-2825,5550)","0","pure_quanta_power","I237";
;
ROOM"MEM_EFGH_DECOUPLING_CAPS"
SIZE"1B"
BOM_COST"MEM"
CDS_LIB"pure_quanta_power"
HDL_POWER"GND";
"A<SIZE-1..0>\NAC"170;
%"Q_CAP"
"1","(-2825,5900)","2","pure_quanta","I238";
;
LOCATION"C162"
$SEC"1"
CDS_SEC"1"
MATERIAL"X6S"
TOLERANCE"10%"
VALUE"10UF"
VOLTAGE"25V"
PACK_TYPE"C0805"
BOM_COST"MEM"
CDS_LIB"pure_quanta"
ROOM""
PART_NUMBER"CH6104KEA00";
"B"
$PN"2"170;
"A"
$PN"1"171;
%"Q_CAP"
"1","(-2250,5900)","2","pure_quanta","I239";
;
LOCATION"C163"
$SEC"1"
CDS_SEC"1"
MATERIAL"X6S"
TOLERANCE"10%"
VALUE"10UF"
VOLTAGE"25V"
PACK_TYPE"C0805"
BOM_COST"MEM"
CDS_LIB"pure_quanta"
ROOM""
PART_NUMBER"CH6104KEA00";
"B"
$PN"2"170;
"A"
$PN"1"171;
%"TAP"
"1","(-7700,3400)","2","mstr_standard","I24";
;
CDS_LIB"mstr_standard"
BODY_TYPE"PLUMBING"
HDL_TAP"TRUE";
"B \NAC \NWC"5;
"S \NAC"
BN"3"141;
%"UNIVERSAL_POWER"
"1","(-2825,6225)","0","pure_quanta_power","I240";
;
HDL_POWER"P12V_MEM_CPU0"
CDS_LIB"pure_quanta_power"
BOM_COST"VR_SYSTEM";
"A"171;
%"Q_RES"
"1","(-7750,2675)","0","pure_quanta","I242";
;
LOCATION"R1576"
$SEC"1"
CDS_SEC"1"
VALUE"49.9"
TOLERANCE"1%"
WATTAGE"1/16W"
PACK_TYPE"0402LF"
MATERIAL"CHIP"
CDS_LIB"pure_quanta"
PART_NUMBER"CS04992FB07";
"B"
$PN"2"20;
"A"
$PN"1"18;
%"Q_RES"
"1","(-8150,2900)","0","pure_quanta","I243";
;
LOCATION"R1683"
$SEC"1"
CDS_SEC"1"
MATERIAL"CHIP"
PACK_TYPE"0402LF"
VALUE"10"
WATTAGE"1/16W"
TOLERANCE"1%"
CDS_LIB"pure_quanta"
PART_NUMBER"CS01002FB07";
"B"
$PN"2"17;
"A"
$PN"1"15;
%"TAP"
"1","(-7700,3300)","2","mstr_standard","I25";
;
CDS_LIB"mstr_standard"
BODY_TYPE"PLUMBING"
HDL_TAP"TRUE";
"B \NAC \NWC"5;
"S \NAC"
BN"1"140;
%"TAP"
"1","(-7700,3250)","2","mstr_standard","I26";
;
CDS_LIB"mstr_standard"
BODY_TYPE"PLUMBING"
HDL_TAP"TRUE";
"B \NAC \NWC"5;
"S \NAC"
BN"0"13;
%"TAP"
"1","(-7700,3450)","2","mstr_standard","I27";
;
CDS_LIB"mstr_standard"
BODY_TYPE"PLUMBING"
HDL_TAP"TRUE";
"B \NAC \NWC"5;
"S \NAC"
BN"4"142;
%"TAP"
"1","(-7700,3500)","2","mstr_standard","I28";
;
CDS_LIB"mstr_standard"
BODY_TYPE"PLUMBING"
HDL_TAP"TRUE";
"B \NAC \NWC"5;
"S \NAC"
BN"5"143;
%"TAP"
"1","(-7700,3550)","2","mstr_standard","I29";
;
CDS_LIB"mstr_standard"
BODY_TYPE"PLUMBING"
HDL_TAP"TRUE";
"B \NAC \NWC"5;
"S \NAC"
BN"6"144;
%"TAP"
"1","(-7700,3600)","2","mstr_standard","I30";
;
CDS_LIB"mstr_standard"
BODY_TYPE"PLUMBING"
HDL_TAP"TRUE";
"B \NAC \NWC"5;
"S \NAC"
BN"7"161;
%"TAP"
"1","(-7700,3700)","2","mstr_standard","I31";
;
CDS_LIB"mstr_standard"
BODY_TYPE"PLUMBING"
HDL_TAP"TRUE";
"B \NAC \NWC"4;
"S \NAC"
BN"0"145;
%"TAP"
"1","(-7700,3750)","2","mstr_standard","I32";
;
CDS_LIB"mstr_standard"
BODY_TYPE"PLUMBING"
HDL_TAP"TRUE";
"B \NAC \NWC"4;
"S \NAC"
BN"1"162;
%"TAP"
"1","(-7700,3800)","2","mstr_standard","I33";
;
CDS_LIB"mstr_standard"
BODY_TYPE"PLUMBING"
HDL_TAP"TRUE";
"B \NAC \NWC"4;
"S \NAC"
BN"2"146;
%"TAP"
"1","(-7700,3850)","2","mstr_standard","I34";
;
CDS_LIB"mstr_standard"
BODY_TYPE"PLUMBING"
HDL_TAP"TRUE";
"B \NAC \NWC"4;
"S \NAC"
BN"3"28;
%"TAP"
"1","(-7700,3900)","2","mstr_standard","I35";
;
CDS_LIB"mstr_standard"
BODY_TYPE"PLUMBING"
HDL_TAP"TRUE";
"B \NAC \NWC"4;
"S \NAC"
BN"4"163;
%"TAP"
"1","(-6000,2250)","0","mstr_standard","I36";
;
CDS_LIB"mstr_standard"
BODY_TYPE"PLUMBING"
HDL_TAP"TRUE";
"B \NAC \NWC"8;
"S \NAC"
BN"0"72;
%"TAP"
"1","(-6000,2350)","0","mstr_standard","I37";
;
CDS_LIB"mstr_standard"
BODY_TYPE"PLUMBING"
HDL_TAP"TRUE";
"B \NAC \NWC"8;
"S \NAC"
BN"2"74;
%"TAP"
"1","(-6000,2400)","0","mstr_standard","I38";
;
CDS_LIB"mstr_standard"
BODY_TYPE"PLUMBING"
HDL_TAP"TRUE";
"B \NAC \NWC"8;
"S \NAC"
BN"3"75;
%"TAP"
"1","(-6000,2300)","0","mstr_standard","I39";
;
CDS_LIB"mstr_standard"
BODY_TYPE"PLUMBING"
HDL_TAP"TRUE";
"B \NAC \NWC"8;
"S \NAC"
BN"1"73;
%"TAP"
"1","(-6000,2450)","0","mstr_standard","I40";
;
CDS_LIB"mstr_standard"
BODY_TYPE"PLUMBING"
HDL_TAP"TRUE";
"B \NAC \NWC"8;
"S \NAC"
BN"4"76;
%"TAP"
"1","(-6000,2500)","0","mstr_standard","I41";
;
CDS_LIB"mstr_standard"
BODY_TYPE"PLUMBING"
HDL_TAP"TRUE";
"B \NAC \NWC"8;
"S \NAC"
BN"5"77;
%"TAP"
"1","(-6000,2550)","0","mstr_standard","I42";
;
CDS_LIB"mstr_standard"
BODY_TYPE"PLUMBING"
HDL_TAP"TRUE";
"B \NAC \NWC"8;
"S \NAC"
BN"6"78;
%"TAP"
"1","(-6000,2600)","0","mstr_standard","I43";
;
CDS_LIB"mstr_standard"
BODY_TYPE"PLUMBING"
HDL_TAP"TRUE";
"B \NAC \NWC"8;
"S \NAC"
BN"7"79;
%"TAP"
"1","(-6000,2650)","0","mstr_standard","I44";
;
CDS_LIB"mstr_standard"
BODY_TYPE"PLUMBING"
HDL_TAP"TRUE";
"B \NAC \NWC"8;
"S \NAC"
BN"8"80;
%"TAP"
"1","(-6000,2700)","0","mstr_standard","I45";
;
CDS_LIB"mstr_standard"
BODY_TYPE"PLUMBING"
HDL_TAP"TRUE";
"B \NAC \NWC"8;
"S \NAC"
BN"9"81;
%"TAP"
"1","(-6000,2750)","0","mstr_standard","I46";
;
CDS_LIB"mstr_standard"
BODY_TYPE"PLUMBING"
HDL_TAP"TRUE";
"B \NAC \NWC"8;
"S \NAC"
BN"10"82;
%"TAP"
"1","(-6000,2800)","0","mstr_standard","I47";
;
CDS_LIB"mstr_standard"
BODY_TYPE"PLUMBING"
HDL_TAP"TRUE";
"B \NAC \NWC"8;
"S \NAC"
BN"11"83;
%"TAP"
"1","(-6000,2900)","0","mstr_standard","I48";
;
CDS_LIB"mstr_standard"
BODY_TYPE"PLUMBING"
HDL_TAP"TRUE";
"B \NAC \NWC"8;
"S \NAC"
BN"13"85;
%"TAP"
"1","(-6000,2850)","0","mstr_standard","I49";
;
CDS_LIB"mstr_standard"
BODY_TYPE"PLUMBING"
HDL_TAP"TRUE";
"B \NAC \NWC"8;
"S \NAC"
BN"12"84;
%"TAP"
"1","(-6000,2950)","0","mstr_standard","I50";
;
CDS_LIB"mstr_standard"
BODY_TYPE"PLUMBING"
HDL_TAP"TRUE";
"B \NAC \NWC"8;
"S \NAC"
BN"14"86;
%"TAP"
"1","(-6000,3000)","0","mstr_standard","I51";
;
CDS_LIB"mstr_standard"
BODY_TYPE"PLUMBING"
HDL_TAP"TRUE";
"B \NAC \NWC"8;
"S \NAC"
BN"15"87;
%"TAP"
"1","(-6000,3050)","0","mstr_standard","I52";
;
CDS_LIB"mstr_standard"
BODY_TYPE"PLUMBING"
HDL_TAP"TRUE";
"B \NAC \NWC"8;
"S \NAC"
BN"16"88;
%"TAP"
"1","(-6000,3100)","0","mstr_standard","I53";
;
CDS_LIB"mstr_standard"
BODY_TYPE"PLUMBING"
HDL_TAP"TRUE";
"B \NAC \NWC"8;
"S \NAC"
BN"17"89;
%"TAP"
"1","(-6000,3150)","0","mstr_standard","I54";
;
CDS_LIB"mstr_standard"
BODY_TYPE"PLUMBING"
HDL_TAP"TRUE";
"B \NAC \NWC"8;
"S \NAC"
BN"18"90;
%"TAP"
"1","(-6000,3200)","0","mstr_standard","I55";
;
CDS_LIB"mstr_standard"
BODY_TYPE"PLUMBING"
HDL_TAP"TRUE";
"B \NAC \NWC"8;
"S \NAC"
BN"19"91;
%"TAP"
"1","(-6000,3250)","0","mstr_standard","I56";
;
CDS_LIB"mstr_standard"
BODY_TYPE"PLUMBING"
HDL_TAP"TRUE";
"B \NAC \NWC"8;
"S \NAC"
BN"20"92;
%"TAP"
"1","(-6000,3300)","0","mstr_standard","I57";
;
CDS_LIB"mstr_standard"
BODY_TYPE"PLUMBING"
HDL_TAP"TRUE";
"B \NAC \NWC"8;
"S \NAC"
BN"21"93;
%"TAP"
"1","(-6000,3350)","0","mstr_standard","I58";
;
CDS_LIB"mstr_standard"
BODY_TYPE"PLUMBING"
HDL_TAP"TRUE";
"B \NAC \NWC"8;
"S \NAC"
BN"22"94;
%"TAP"
"1","(-6000,3400)","0","mstr_standard","I59";
;
CDS_LIB"mstr_standard"
BODY_TYPE"PLUMBING"
HDL_TAP"TRUE";
"B \NAC \NWC"8;
"S \NAC"
BN"23"95;
%"TAP"
"1","(-6000,3450)","0","mstr_standard","I60";
;
CDS_LIB"mstr_standard"
BODY_TYPE"PLUMBING"
HDL_TAP"TRUE";
"B \NAC \NWC"8;
"S \NAC"
BN"24"96;
%"TAP"
"1","(-6000,3500)","0","mstr_standard","I61";
;
CDS_LIB"mstr_standard"
BODY_TYPE"PLUMBING"
HDL_TAP"TRUE";
"B \NAC \NWC"8;
"S \NAC"
BN"25"97;
%"TAP"
"1","(-6000,3550)","0","mstr_standard","I62";
;
CDS_LIB"mstr_standard"
BODY_TYPE"PLUMBING"
HDL_TAP"TRUE";
"B \NAC \NWC"8;
"S \NAC"
BN"26"98;
%"TAP"
"1","(-6000,3600)","0","mstr_standard","I63";
;
CDS_LIB"mstr_standard"
BODY_TYPE"PLUMBING"
HDL_TAP"TRUE";
"B \NAC \NWC"8;
"S \NAC"
BN"27"99;
%"TAP"
"1","(-6000,3650)","0","mstr_standard","I64";
;
CDS_LIB"mstr_standard"
BODY_TYPE"PLUMBING"
HDL_TAP"TRUE";
"B \NAC \NWC"8;
"S \NAC"
BN"28"100;
%"TAP"
"1","(-6000,3700)","0","mstr_standard","I65";
;
CDS_LIB"mstr_standard"
BODY_TYPE"PLUMBING"
HDL_TAP"TRUE";
"B \NAC \NWC"8;
"S \NAC"
BN"29"101;
%"TAP"
"1","(-6000,3800)","0","mstr_standard","I66";
;
CDS_LIB"mstr_standard"
BODY_TYPE"PLUMBING"
HDL_TAP"TRUE";
"B \NAC \NWC"8;
"S \NAC"
BN"31"103;
%"TAP"
"1","(-6000,3750)","0","mstr_standard","I67";
;
CDS_LIB"mstr_standard"
BODY_TYPE"PLUMBING"
HDL_TAP"TRUE";
"B \NAC \NWC"8;
"S \NAC"
BN"30"102;
%"TAP"
"1","(-6000,3900)","0","mstr_standard","I68";
;
CDS_LIB"mstr_standard"
BODY_TYPE"PLUMBING"
HDL_TAP"TRUE";
"B \NAC \NWC"3;
"S \NAC"
BN"0"104;
%"TAP"
"1","(-7700,4050)","2","mstr_standard","I77";
;
CDS_LIB"mstr_standard"
BODY_TYPE"PLUMBING"
HDL_TAP"TRUE";
"B \NAC \NWC"4;
"S \NAC"
BN"7"164;
%"TAP"
"1","(-7700,4000)","2","mstr_standard","I78";
;
CDS_LIB"mstr_standard"
BODY_TYPE"PLUMBING"
HDL_TAP"TRUE";
"B \NAC \NWC"4;
"S \NAC"
BN"6"27;
%"TAP"
"1","(-7700,3950)","2","mstr_standard","I79";
;
CDS_LIB"mstr_standard"
BODY_TYPE"PLUMBING"
HDL_TAP"TRUE";
"B \NAC \NWC"4;
"S \NAC"
BN"5"147;
%"TAP"
"1","(-7700,4900)","2","mstr_standard","I80";
;
CDS_LIB"mstr_standard"
BODY_TYPE"PLUMBING"
HDL_TAP"TRUE";
"B \NAC \NWC"7;
"S \NAC"
BN"3"153;
%"TAP"
"1","(-7700,4850)","2","mstr_standard","I81";
;
CDS_LIB"mstr_standard"
BODY_TYPE"PLUMBING"
HDL_TAP"TRUE";
"B \NAC \NWC"7;
"S \NAC"
BN"2"155;
%"TAP"
"1","(-7700,4800)","2","mstr_standard","I82";
;
CDS_LIB"mstr_standard"
BODY_TYPE"PLUMBING"
HDL_TAP"TRUE";
"B \NAC \NWC"7;
"S \NAC"
BN"1"157;
%"TAP"
"1","(-7700,4750)","2","mstr_standard","I83";
;
CDS_LIB"mstr_standard"
BODY_TYPE"PLUMBING"
HDL_TAP"TRUE";
"B \NAC \NWC"7;
"S \NAC"
BN"0"159;
%"TAP"
"1","(-7700,4950)","2","mstr_standard","I84";
;
CDS_LIB"mstr_standard"
BODY_TYPE"PLUMBING"
HDL_TAP"TRUE";
"B \NAC \NWC"7;
"S \NAC"
BN"4"29;
%"TAP"
"1","(-7700,5000)","2","mstr_standard","I85";
;
CDS_LIB"mstr_standard"
BODY_TYPE"PLUMBING"
HDL_TAP"TRUE";
"B \NAC \NWC"7;
"S \NAC"
BN"5"150;
%"TAP"
"1","(-7700,5050)","2","mstr_standard","I86";
;
CDS_LIB"mstr_standard"
BODY_TYPE"PLUMBING"
HDL_TAP"TRUE";
"B \NAC \NWC"7;
"S \NAC"
BN"6"148;
%"TAP"
"1","(-7700,5200)","2","mstr_standard","I87";
;
CDS_LIB"mstr_standard"
BODY_TYPE"PLUMBING"
HDL_TAP"TRUE";
"B \NAC \NWC"6;
"S \NAC"
BN"1"158;
%"TAP"
"1","(-7700,5150)","2","mstr_standard","I88";
;
CDS_LIB"mstr_standard"
BODY_TYPE"PLUMBING"
HDL_TAP"TRUE";
"B \NAC \NWC"6;
"S \NAC"
BN"0"160;
%"TAP"
"1","(-7700,5250)","2","mstr_standard","I89";
;
CDS_LIB"mstr_standard"
BODY_TYPE"PLUMBING"
HDL_TAP"TRUE";
"B \NAC \NWC"6;
"S \NAC"
BN"2"156;
%"VCC_CORE"
"1","(-8550,3475)","0","mstr_symbols","I9";
;
HDL_POWER"P3V3_AUX"
ROOM"PVCCINFAON_CPU0_CTRL"
VOLTAGE"3.3"
CDS_LIB"mstr_symbols";
"A"14;
%"TAP"
"1","(-7700,5300)","2","mstr_standard","I90";
;
CDS_LIB"mstr_standard"
BODY_TYPE"PLUMBING"
HDL_TAP"TRUE";
"B \NAC \NWC"6;
"S \NAC"
BN"3"154;
%"TAP"
"1","(-7700,5350)","2","mstr_standard","I91";
;
CDS_LIB"mstr_standard"
BODY_TYPE"PLUMBING"
HDL_TAP"TRUE";
"B \NAC \NWC"6;
"S \NAC"
BN"4"152;
%"TAP"
"1","(-7700,5450)","2","mstr_standard","I92";
;
CDS_LIB"mstr_standard"
BODY_TYPE"PLUMBING"
HDL_TAP"TRUE";
"B \NAC \NWC"6;
"S \NAC"
BN"6"149;
%"TAP"
"1","(-7700,5400)","2","mstr_standard","I93";
;
CDS_LIB"mstr_standard"
BODY_TYPE"PLUMBING"
HDL_TAP"TRUE";
"B \NAC \NWC"6;
"S \NAC"
BN"5"151;
%"TAP"
"1","(-6000,3950)","0","mstr_standard","I94";
;
CDS_LIB"mstr_standard"
BODY_TYPE"PLUMBING"
HDL_TAP"TRUE";
"B \NAC \NWC"3;
"S \NAC"
BN"1"105;
%"TAP"
"1","(-6000,4000)","0","mstr_standard","I95";
;
CDS_LIB"mstr_standard"
BODY_TYPE"PLUMBING"
HDL_TAP"TRUE";
"B \NAC \NWC"3;
"S \NAC"
BN"2"106;
%"TAP"
"1","(-6000,4050)","0","mstr_standard","I96";
;
CDS_LIB"mstr_standard"
BODY_TYPE"PLUMBING"
HDL_TAP"TRUE";
"B \NAC \NWC"3;
"S \NAC"
BN"3"107;
%"TAP"
"1","(-6000,4200)","0","mstr_standard","I97";
;
CDS_LIB"mstr_standard"
BODY_TYPE"PLUMBING"
HDL_TAP"TRUE";
"B \NAC \NWC"3;
"S \NAC"
BN"6"110;
%"TAP"
"1","(-6000,4100)","0","mstr_standard","I98";
;
CDS_LIB"mstr_standard"
BODY_TYPE"PLUMBING"
HDL_TAP"TRUE";
"B \NAC \NWC"3;
"S \NAC"
BN"4"108;
%"TAP"
"1","(-6000,4150)","0","mstr_standard","I99";
;
CDS_LIB"mstr_standard"
BODY_TYPE"PLUMBING"
HDL_TAP"TRUE";
"B \NAC \NWC"3;
"S \NAC"
BN"5"109;
END.
